# T6G (Grand Teton) — schematic parts with pin connectivity, parts 8082–8082 of 8303; source: Cadence DE-HDL packaged netlist (pstxprt.dat, pstxnet.dat, pstchip.dat)

U26  GENOA_SP5  SOCKET6096_13568-001 IO  pkg SOCKET6096_93-4X120-45XA  page 37  (pins 2353-2688 of 6096)
  BR58  VDDIO_BR58  POWER  = PVDDIO_P1
  BR59  VSS_BR59  POWER  = GND
  BR60  MDB1_RSP_L  IN  = NC
  BR61  VSS_BR61  POWER  = GND
  BR62  VSS_BR62  POWER  = GND
  BR63  VSS_BR63  POWER  = GND
  BR64  MBB1_RSP_L  IN  = NC
  BR65  VDDIO_BR65  POWER  = PVDDIO_P1
  BR66  VSS_BR66  POWER  = GND
  BR67  MFB1_RSP_L  IN  = NC
  BR68  VSS_BR68  POWER  = GND
  BR69  VSS_BR69  POWER  = GND
  BR70  VSS_BR70  POWER  = GND
  BR71  MEB1_RSP_L  IN  = NC
  BR72  VDDIO_BR72  POWER  = PVDDIO_P1
  BR73  VSS_BR73  POWER  = GND
  BR74  MAB1_RSP_L  IN  = NC
  BR75  VSS_BR75  POWER  = GND
  BT2  MGB_CHECK4  BI  = M_G_CPU1_SB_CB<4>
  BT3  VSS_BT3  POWER  = GND
  BT4  VSS_BT4  POWER  = GND
  BT5  VSS_BT5  POWER  = GND
  BT6  MKB_CHECK4  BI  = M_K_CPU1_SB_CB<4>
  BT7  VSS_BT7  POWER  = GND
  BT8  VSS_BT8  POWER  = GND
  BT9  MLB_CHECK4  BI  = M_L_CPU1_SB_CB<4>
  BT10  VSS_BT10  POWER  = GND
  BT11  VSS_BT11  POWER  = GND
  BT12  VSS_BT12  POWER  = GND
  BT13  MHB_CHECK4  BI  = M_H_CPU1_SB_CB<4>
  BT14  VSS_BT14  POWER  = GND
  BT15  VSS_BT15  POWER  = GND
  BT16  MJB_CHECK4  BI  = M_J_CPU1_SB_CB<4>
  BT17  VSS_BT17  POWER  = GND
  BT18  VSS_BT18  POWER  = GND
  BT19  VSS_BT19  POWER  = GND
  BT20  MIB_CHECK4  BI  = M_I_CPU1_SB_CB<4>
  BT21  VSS_BT21  POWER  = GND
  BT22  VSS_BT22  POWER  = GND
  BT23  VDDCR_CPU1_BT23  POWER  = PVDDCR_CPU1_P1
  BT24  VDDCR_CPU1_BT24  POWER  = PVDDCR_CPU1_P1
  BT25  VSS_BT25  POWER  = GND
  BT26  VDDCR_CPU1_BT26  POWER  = PVDDCR_CPU1_P1
  BT27  VDDCR_CPU1_BT27  POWER  = PVDDCR_CPU1_P1
  BT28  VSS_BT28  POWER  = GND
  BT29  VDDCR_CPU1_BT29  POWER  = PVDDCR_CPU1_P1
  BT30  VDDCR_CPU1_BT30  POWER  = PVDDCR_CPU1_P1
  BT31  VSS_BT31  POWER  = GND
  BT32  VDDCR_CPU1_BT32  POWER  = PVDDCR_CPU1_P1
  BT33  VDDCR_CPU1_BT33  POWER  = PVDDCR_CPU1_P1
  BT34  VSS_BT34  POWER  = GND
  BT35  P2_TXN0  OUT  = P5E_CPU1_P2_TX_DN<0>
  BT36  P2_TXP0  OUT  = P5E_CPU1_P2_TX_DP<0>
  BT37  VSS_BT37  POWER  = GND
  BT39  VSS_BT39  POWER  = GND
  BT40  \p0_rxp15||sata17_rxp\  IN  = P5E_CPU1_P0_RX_DP<15>
  BT41  \p0_rxn15||sata17_rxn\  IN  = P5E_CPU1_P0_RX_DN<15>
  BT42  VSS_BT42  POWER  = GND
  BT43  VDDCR_CPU1_BT43  POWER  = PVDDCR_CPU1_P1
  BT44  VDDCR_CPU1_BT44  POWER  = PVDDCR_CPU1_P1
  BT45  VSS_BT45  POWER  = GND
  BT46  VDDCR_CPU1_BT46  POWER  = PVDDCR_CPU1_P1
  BT47  VDDCR_CPU1_BT47  POWER  = PVDDCR_CPU1_P1
  BT48  VSS_BT48  POWER  = GND
  BT49  VDDCR_CPU1_BT49  POWER  = PVDDCR_CPU1_P1
  BT50  VDDCR_CPU1_BT50  POWER  = PVDDCR_CPU1_P1
  BT51  VSS_BT51  POWER  = GND
  BT52  VDDCR_CPU1_BT52  POWER  = PVDDCR_CPU1_P1
  BT53  VDDCR_CPU1_BT53  POWER  = PVDDCR_CPU1_P1
  BT54  VSS_BT54  POWER  = GND
  BT55  VSS_BT55  POWER  = GND
  BT56  MCB_CHECK4  BI  = M_C_CPU1_SB_CB<4>
  BT57  VSS_BT57  POWER  = GND
  BT58  VSS_BT58  POWER  = GND
  BT59  VSS_BT59  POWER  = GND
  BT60  MDB_CHECK4  BI  = M_D_CPU1_SB_CB<4>
  BT61  VSS_BT61  POWER  = GND
  BT62  VSS_BT62  POWER  = GND
  BT63  MBB_CHECK4  BI  = M_B_CPU1_SB_CB<4>
  BT64  VSS_BT64  POWER  = GND
  BT65  VSS_BT65  POWER  = GND
  BT66  VSS_BT66  POWER  = GND
  BT67  MFB_CHECK4  BI  = M_F_CPU1_SB_CB<4>
  BT68  VSS_BT68  POWER  = GND
  BT69  VSS_BT69  POWER  = GND
  BT70  MEB_CHECK4  BI  = M_E_CPU1_SB_CB<4>
  BT71  VSS_BT71  POWER  = GND
  BT72  VSS_BT72  POWER  = GND
  BT73  VSS_BT73  POWER  = GND
  BT74  MAB_CHECK4  BI  = M_A_CPU1_SB_CB<4>
  BU1  VSS_BU1  POWER  = GND
  BU2  MGB_CHECK6  BI  = M_G_CPU1_SB_CB<6>
  BU3  MGB_CHECK5  BI  = M_G_CPU1_SB_CB<5>
  BU4  VSS_BU4  POWER  = GND
  BU5  MKB_CHECK6  BI  = M_K_CPU1_SB_CB<6>
  BU6  VSS_BU6  POWER  = GND
  BU7  MKB_CHECK5  BI  = M_K_CPU1_SB_CB<5>
  BU8  VSS_BU8  POWER  = GND
  BU9  MLB_CHECK6  BI  = M_L_CPU1_SB_CB<6>
  BU10  MLB_CHECK5  BI  = M_L_CPU1_SB_CB<5>
  BU11  VSS_BU11  POWER  = GND
  BU12  MHB_CHECK6  BI  = M_H_CPU1_SB_CB<6>
  BU13  VSS_BU13  POWER  = GND
  BU14  MHB_CHECK5  BI  = M_H_CPU1_SB_CB<5>
  BU15  VSS_BU15  POWER  = GND
  BU16  MJB_CHECK6  BI  = M_J_CPU1_SB_CB<6>
  BU17  MJB_CHECK5  BI  = M_J_CPU1_SB_CB<5>
  BU18  VSS_BU18  POWER  = GND
  BU19  MIB_CHECK6  BI  = M_I_CPU1_SB_CB<6>
  BU20  VSS_BU20  POWER  = GND
  BU21  MIB_CHECK5  BI  = M_I_CPU1_SB_CB<5>
  BU22  VSS_BU22  POWER  = GND
  BU23  P2_TXN13  OUT  = P5E_CPU1_P2_TX_DN<13>
  BU24  P2_TXP13  OUT  = P5E_CPU1_P2_TX_DP<13>
  BU25  VSS_BU25  POWER  = GND
  BU26  P2_TXN10  OUT  = P5E_CPU1_P2_TX_DN<10>
  BU27  P2_TXP10  OUT  = P5E_CPU1_P2_TX_DP<10>
  BU28  VSS_BU28  POWER  = GND
  BU29  P2_TXN7  OUT  = P5E_CPU1_P2_TX_DN<7>
  BU30  P2_TXP7  OUT  = P5E_CPU1_P2_TX_DP<7>
  BU31  VSS_BU31  POWER  = GND
  BU32  P2_TXN4  OUT  = P5E_CPU1_P2_TX_DN<4>
  BU33  P2_TXP4  OUT  = P5E_CPU1_P2_TX_DP<4>
  BU34  VSS_BU34  POWER  = GND
  BU35  VSS_BU35  POWER  = GND
  BU36  VSS_BU36  POWER  = GND
  BU40  VSS_BU40  POWER  = GND
  BU41  VSS_BU41  POWER  = GND
  BU42  VSS_BU42  POWER  = GND
  BU43  \p0_rxp11||sata13_rxp\  IN  = P5E_CPU1_P0_RX_DP<11>
  BU44  \p0_rxn11||sata13_rxn\  IN  = P5E_CPU1_P0_RX_DN<11>
  BU45  VSS_BU45  POWER  = GND
  BU46  \p0_rxp8||sata10_rxp\  IN  = P5E_CPU1_P0_RX_DP<8>
  BU47  \p0_rxn8||sata10_rxn\  IN  = P5E_CPU1_P0_RX_DN<8>
  BU48  VSS_BU48  POWER  = GND
  BU49  \p0_rxp5||sata05_rxp\  IN  = P5E_CPU1_P0_RX_DP<5>
  BU50  \p0_rxn5||sata05_rxn\  IN  = P5E_CPU1_P0_RX_DN<5>
  BU51  VSS_BU51  POWER  = GND
  BU52  \p0_rxp2||sata02_rxp\  IN  = P5E_CPU1_P0_RX_DP<2>
  BU53  \p0_rxn2||sata02_rxn\  IN  = P5E_CPU1_P0_RX_DN<2>
  BU54  VSS_BU54  POWER  = GND
  BU55  MCB_CHECK5  BI  = M_C_CPU1_SB_CB<5>
  BU56  VSS_BU56  POWER  = GND
  BU57  MCB_CHECK6  BI  = M_C_CPU1_SB_CB<6>
  BU58  VSS_BU58  POWER  = GND
  BU59  MDB_CHECK5  BI  = M_D_CPU1_SB_CB<5>
  BU60  MDB_CHECK6  BI  = M_D_CPU1_SB_CB<6>
  BU61  VSS_BU61  POWER  = GND
  BU62  MBB_CHECK5  BI  = M_B_CPU1_SB_CB<5>
  BU63  VSS_BU63  POWER  = GND
  BU64  MBB_CHECK6  BI  = M_B_CPU1_SB_CB<6>
  BU65  VSS_BU65  POWER  = GND
  BU66  MFB_CHECK5  BI  = M_F_CPU1_SB_CB<5>
  BU67  MFB_CHECK6  BI  = M_F_CPU1_SB_CB<6>
  BU68  VSS_BU68  POWER  = GND
  BU69  MEB_CHECK5  BI  = M_E_CPU1_SB_CB<5>
  BU70  VSS_BU70  POWER  = GND
  BU71  MEB_CHECK6  BI  = M_E_CPU1_SB_CB<6>
  BU72  VSS_BU72  POWER  = GND
  BU73  MAB_CHECK5  BI  = M_A_CPU1_SB_CB<5>
  BU74  MAB_CHECK6  BI  = M_A_CPU1_SB_CB<6>
  BU75  VSS_BU75  POWER  = GND
  BV2  MGB_DQS_H9  BI  = M_G_CPU1_SB_DQS_DP<9>
  BV3  VSS_BV3  POWER  = GND
  BV4  MGB_CHECK7  BI  = M_G_CPU1_SB_CB<7>
  BV5  VDD_11_S3_BV5  POWER  = PVDD11_S3_P1
  BV6  MKB_DQS_H9  BI  = M_K_CPU1_SB_DQS_DP<9>
  BV7  MKB_CHECK7  BI  = M_K_CPU1_SB_CB<7>
  BV8  VSS_BV8  POWER  = GND
  BV9  MLB_DQS_H9  BI  = M_L_CPU1_SB_DQS_DP<9>
  BV10  VSS_BV10  POWER  = GND
  BV11  MLB_CHECK7  BI  = M_L_CPU1_SB_CB<7>
  BV12  VDD_11_S3_BV12  POWER  = PVDD11_S3_P1
  BV13  MHB_DQS_H9  BI  = M_H_CPU1_SB_DQS_DP<9>
  BV14  MHB_CHECK7  BI  = M_H_CPU1_SB_CB<7>
  BV15  VSS_BV15  POWER  = GND
  BV16  MJB_DQS_H9  BI  = M_J_CPU1_SB_DQS_DP<9>
  BV17  VSS_BV17  POWER  = GND
  BV18  MJB_CHECK7  BI  = M_J_CPU1_SB_CB<7>
  BV19  VDD_11_S3_BV19  POWER  = PVDD11_S3_P1
  BV20  MIB_DQS_H9  BI  = M_I_CPU1_SB_DQS_DP<9>
  BV21  MIB_CHECK7  BI  = M_I_CPU1_SB_CB<7>
  BV22  VDD_11_S3_BV22  POWER  = PVDD11_S3_P1
  BV23  VSS_BV23  POWER  = GND
  BV24  VSS_BV24  POWER  = GND
  BV25  VSS_BV25  POWER  = GND
  BV26  VSS_BV26  POWER  = GND
  BV27  VSS_BV27  POWER  = GND
  BV28  VSS_BV28  POWER  = GND
  BV29  VSS_BV29  POWER  = GND
  BV30  VSS_BV30  POWER  = GND
  BV31  VSS_BV31  POWER  = GND
  BV32  VSS_BV32  POWER  = GND
  BV33  VSS_BV33  POWER  = GND
  BV34  VSS_BV34  POWER  = GND
  BV35  P2_TXN1  OUT  = P5E_CPU1_P2_TX_DN<1>
  BV36  P2_TXP1  OUT  = P5E_CPU1_P2_TX_DP<1>
  BV37  VSS_BV37  POWER  = GND
  BV39  VSS_BV39  POWER  = GND
  BV40  \p0_rxp14||sata16_rxp\  IN  = P5E_CPU1_P0_RX_DP<14>
  BV41  \p0_rxn14||sata16_rxn\  IN  = P5E_CPU1_P0_RX_DN<14>
  BV42  VSS_BV42  POWER  = GND
  BV43  VSS_BV43  POWER  = GND
  BV44  VSS_BV44  POWER  = GND
  BV45  VSS_BV45  POWER  = GND
  BV46  VSS_BV46  POWER  = GND
  BV47  VSS_BV47  POWER  = GND
  BV48  VSS_BV48  POWER  = GND
  BV49  VSS_BV49  POWER  = GND
  BV50  VSS_BV50  POWER  = GND
  BV51  VSS_BV51  POWER  = GND
  BV52  VSS_BV52  POWER  = GND
  BV53  VSS_BV53  POWER  = GND
  BV54  VDDIO_BV54  POWER  = PVDDIO_P1
  BV55  MCB_CHECK7  BI  = M_C_CPU1_SB_CB<7>
  BV56  MCB_DQS_H9  BI  = M_C_CPU1_SB_DQS_DP<9>
  BV57  VDDIO_BV57  POWER  = PVDDIO_P1
  BV58  MDB_CHECK7  BI  = M_D_CPU1_SB_CB<7>
  BV59  VSS_BV59  POWER  = GND
  BV60  MDB_DQS_H9  BI  = M_D_CPU1_SB_DQS_DP<9>
  BV61  VSS_BV61  POWER  = GND
  BV62  MBB_CHECK7  BI  = M_B_CPU1_SB_CB<7>
  BV63  MBB_DQS_H9  BI  = M_B_CPU1_SB_DQS_DP<9>
  BV64  VDDIO_BV64  POWER  = PVDDIO_P1
  BV65  MFB_CHECK7  BI  = M_F_CPU1_SB_CB<7>
  BV66  VSS_BV66  POWER  = GND
  BV67  MFB_DQS_H9  BI  = M_F_CPU1_SB_DQS_DP<9>
  BV68  VSS_BV68  POWER  = GND
  BV69  MEB_CHECK7  BI  = M_E_CPU1_SB_CB<7>
  BV70  MEB_DQS_H9  BI  = M_E_CPU1_SB_DQS_DP<9>
  BV71  VDDIO_BV71  POWER  = PVDDIO_P1
  BV72  MAB_CHECK7  BI  = M_A_CPU1_SB_CB<7>
  BV73  VSS_BV73  POWER  = GND
  BV74  MAB_DQS_H9  BI  = M_A_CPU1_SB_DQS_DP<9>
  BW1  VSS_BW1  POWER  = GND
  BW2  MGB_DQS_L9  BI  = M_G_CPU1_SB_DQS_DN<9>
  BW3  MGB_DQS_L4  BI  = M_G_CPU1_SB_DQS_DN<4>
  BW4  VSS_BW4  POWER  = GND
  BW5  MKB_DQS_L9  BI  = M_K_CPU1_SB_DQS_DN<9>
  BW6  VSS_BW6  POWER  = GND
  BW7  MKB_DQS_L4  BI  = M_K_CPU1_SB_DQS_DN<4>
  BW8  VSS_BW8  POWER  = GND
  BW9  MLB_DQS_L9  BI  = M_L_CPU1_SB_DQS_DN<9>
  BW10  MLB_DQS_L4  BI  = M_L_CPU1_SB_DQS_DN<4>
  BW11  VSS_BW11  POWER  = GND
  BW12  MHB_DQS_L9  BI  = M_H_CPU1_SB_DQS_DN<9>
  BW13  VSS_BW13  POWER  = GND
  BW14  MHB_DQS_L4  BI  = M_H_CPU1_SB_DQS_DN<4>
  BW15  VSS_BW15  POWER  = GND
  BW16  MJB_DQS_L9  BI  = M_J_CPU1_SB_DQS_DN<9>
  BW17  MJB_DQS_L4  BI  = M_J_CPU1_SB_DQS_DN<4>
  BW18  VSS_BW18  POWER  = GND
  BW19  MIB_DQS_L9  BI  = M_I_CPU1_SB_DQS_DN<9>
  BW20  VSS_BW20  POWER  = GND
  BW21  MIB_DQS_L4  BI  = M_I_CPU1_SB_DQS_DN<4>
  BW22  VSS_BW22  POWER  = GND
  BW23  P2_TXN15  OUT  = P5E_CPU1_P2_TX_DN<15>
  BW24  P2_TXP15  OUT  = P5E_CPU1_P2_TX_DP<15>
  BW25  VSS_BW25  POWER  = GND
  BW26  P2_TXN12  OUT  = P5E_CPU1_P2_TX_DN<12>
  BW27  P2_TXP12  OUT  = P5E_CPU1_P2_TX_DP<12>
  BW28  VSS_BW28  POWER  = GND
  BW29  P2_TXN9  OUT  = P5E_CPU1_P2_TX_DN<9>
  BW30  P2_TXP9  OUT  = P5E_CPU1_P2_TX_DP<9>
  BW31  VSS_BW31  POWER  = GND
  BW32  P2_TXN6  OUT  = P5E_CPU1_P2_TX_DN<6>
  BW33  P2_TXP6  OUT  = P5E_CPU1_P2_TX_DP<6>
  BW34  VSS_BW34  POWER  = GND
  BW35  VDDCR_CPU1_BW35  POWER  = PVDDCR_CPU1_P1
  BW36  VDDCR_CPU1_BW36  POWER  = PVDDCR_CPU1_P1
  BW40  VDDCR_CPU1_BW40  POWER  = PVDDCR_CPU1_P1
  BW41  VDDCR_CPU1_BW41  POWER  = PVDDCR_CPU1_P1
  BW42  VSS_BW42  POWER  = GND
  BW43  \p0_rxp9||sata11_rxp\  IN  = P5E_CPU1_P0_RX_DP<9>
  BW44  \p0_rxn9||sata11_rxn\  IN  = P5E_CPU1_P0_RX_DN<9>
  BW45  VSS_BW45  POWER  = GND
  BW46  \p0_rxp6||sata06_rxp\  IN  = P5E_CPU1_P0_RX_DP<6>
  BW47  \p0_rxn6||sata06_rxn\  IN  = P5E_CPU1_P0_RX_DN<6>
  BW48  VSS_BW48  POWER  = GND
  BW49  \p0_rxp3||sata03_rxp\  IN  = P5E_CPU1_P0_RX_DP<3>
  BW50  \p0_rxn3||sata03_rxn\  IN  = P5E_CPU1_P0_RX_DN<3>
  BW51  VSS_BW51  POWER  = GND
  BW52  \p0_rxp0||sata00_rxp\  IN  = P5E_CPU1_P0_RX_DP<0>
  BW53  \p0_rxn0||sata00_rxn\  IN  = P5E_CPU1_P0_RX_DN<0>
  BW54  VSS_BW54  POWER  = GND
  BW55  MCB_DQS_L4  BI  = M_C_CPU1_SB_DQS_DN<4>
  BW56  VSS_BW56  POWER  = GND
  BW57  MCB_DQS_L9  BI  = M_C_CPU1_SB_DQS_DN<9>
  BW58  VSS_BW58  POWER  = GND
  BW59  MDB_DQS_L4  BI  = M_D_CPU1_SB_DQS_DN<4>
  BW60  MDB_DQS_L9  BI  = M_D_CPU1_SB_DQS_DN<9>
  BW61  VSS_BW61  POWER  = GND
  BW62  MBB_DQS_L4  BI  = M_B_CPU1_SB_DQS_DN<4>
  BW63  VSS_BW63  POWER  = GND
  BW64  MBB_DQS_L9  BI  = M_B_CPU1_SB_DQS_DN<9>
  BW65  VSS_BW65  POWER  = GND
  BW66  MFB_DQS_L4  BI  = M_F_CPU1_SB_DQS_DN<4>
  BW67  MFB_DQS_L9  BI  = M_F_CPU1_SB_DQS_DN<9>
  BW68  VSS_BW68  POWER  = GND
  BW69  MEB_DQS_L4  BI  = M_E_CPU1_SB_DQS_DN<4>
  BW70  VSS_BW70  POWER  = GND
  BW71  MEB_DQS_L9  BI  = M_E_CPU1_SB_DQS_DN<9>
  BW72  VSS_BW72  POWER  = GND
  BW73  MAB_DQS_L4  BI  = M_A_CPU1_SB_DQS_DN<4>
  BW74  MAB_DQS_L9  BI  = M_A_CPU1_SB_DQS_DN<9>
  BW75  VSS_BW75  POWER  = GND
  BY2  MGB_CHECK0  BI  = M_G_CPU1_SB_CB<0>
  BY3  VSS_BY3  POWER  = GND
  BY4  MGB_DQS_H4  BI  = M_G_CPU1_SB_DQS_DP<4>
  BY5  VSS_BY5  POWER  = GND
  BY6  MKB_CHECK0  BI  = M_K_CPU1_SB_CB<0>
  BY7  MKB_DQS_H4  BI  = M_K_CPU1_SB_DQS_DP<4>
  BY8  VSS_BY8  POWER  = GND
  BY9  MLB_CHECK0  BI  = M_L_CPU1_SB_CB<0>
  BY10  VSS_BY10  POWER  = GND
  BY11  MLB_DQS_H4  BI  = M_L_CPU1_SB_DQS_DP<4>
  BY12  VSS_BY12  POWER  = GND
  BY13  MHB_CHECK0  BI  = M_H_CPU1_SB_CB<0>
  BY14  MHB_DQS_H4  BI  = M_H_CPU1_SB_DQS_DP<4>
  BY15  VSS_BY15  POWER  = GND
  BY16  MJB_CHECK0  BI  = M_J_CPU1_SB_CB<0>
  BY17  VSS_BY17  POWER  = GND
  BY18  MJB_DQS_H4  BI  = M_J_CPU1_SB_DQS_DP<4>
  BY19  VSS_BY19  POWER  = GND
  BY20  MIB_CHECK0  BI  = M_I_CPU1_SB_CB<0>
  BY21  MIB_DQS_H4  BI  = M_I_CPU1_SB_DQS_DP<4>
  BY22  VSS_BY22  POWER  = GND
  BY23  VDDCR_CPU1_BY23  POWER  = PVDDCR_CPU1_P1
  BY24  VDDCR_CPU1_BY24  POWER  = PVDDCR_CPU1_P1
  BY25  VSS_BY25  POWER  = GND
  BY26  VDDCR_CPU1_BY26  POWER  = PVDDCR_CPU1_P1
  BY27  VDDCR_CPU1_BY27  POWER  = PVDDCR_CPU1_P1
  BY28  VSS_BY28  POWER  = GND
  BY29  VDDCR_CPU1_BY29  POWER  = PVDDCR_CPU1_P1
  BY30  VDDCR_CPU1_BY30  POWER  = PVDDCR_CPU1_P1
  BY31  VSS_BY31  POWER  = GND
